(kicad_pcb
	(version 20260206)
	(generator "pcbnew")
	(generator_version "10.0")
	(general
		(thickness 1.6)
		(legacy_teardrops no)
	)
	(paper "A4")
	(title_block
		(title "m-2 — Lightning_M.2_BRD.brd")
		(comment 1 "Lightning (Wiwynn / Facebook NVMe JBOF) / footprints 147-153 of 157")
	)
	(layers
		(0 "F.Cu" signal "TOP")
		(4 "In1.Cu" signal "L2GND")
		(6 "In2.Cu" signal "L3")
		(8 "In3.Cu" signal "L4GND")
		(10 "In4.Cu" signal "L5GND")
		(12 "In5.Cu" signal "L6")
		(14 "In6.Cu" signal "L7GND")
		(2 "B.Cu" signal "BOTTOM")
		(9 "F.Adhes" user "F.Adhesive")
		(11 "B.Adhes" user "B.Adhesive")
		(13 "F.Paste" user "Package Geometry/Pastemask Top")
		(15 "B.Paste" user "Package Geometry/Pastemask Bottom")
		(5 "F.SilkS" user "Ref Des/Silkscreen Top")
		(7 "B.SilkS" user "Ref Des/Silkscreen Bottom")
		(1 "F.Mask" user "Board Geometry/Soldermask Top")
		(3 "B.Mask" user "Board Geometry/Soldermask Bottom")
		(17 "Dwgs.User" user "User.Drawings")
		(19 "Cmts.User" user "User.Comments")
		(21 "Eco1.User" user "User.Eco1")
		(23 "Eco2.User" user "User.Eco2")
		(25 "Edge.Cuts" user "Board Geometry/Outline")
		(27 "Margin" user)
		(31 "F.CrtYd" user "Package Geometry/Place Bound Top")
		(29 "B.CrtYd" user "Package Geometry/Place Bound Bottom")
		(35 "F.Fab" user "Ref Des/Assembly Top")
		(33 "B.Fab" user "Ref Des/Assembly Bottom")
	)
	(footprint ""
		(layer "B.Cu")
		(at 24.13 -71.755 180)
		(property "Reference" "R35"
			(at 0 0 0)
			(layer "B.SilkS")
			(hide yes)
			(effects
				(font
					(size 1.27 1.27)
				)
				(justify mirror)
			)
		)
		(property "Value" "47KR2F-GP"
			(at -0.064008 -3.993896 180)
			(unlocked yes)
			(layer "B.Fab")
			(hide yes)
			(effects
				(font
					(size 1.016 1.016)
					(thickness 0.1524)
				)
				(justify mirror)
			)
		)
		(property "Device Type" "R402H16"
			(at -0.064008 -5.517896 180)
			(unlocked yes)
			(layer "B.Fab")
			(hide yes)
			(effects
				(font
					(size 1.016 1.016)
					(thickness 0.1524)
				)
				(justify mirror)
			)
		)
		(duplicate_pad_numbers_are_jumpers no)
		(fp_line
			(start 0.508 -0.9398)
			(end 0.508 0.9398)
			(stroke
				(width 0.1524)
				(type default)
			)
			(layer "B.SilkS")
		)
		(fp_line
			(start -0.508 -0.9398)
			(end 0.508 -0.9398)
			(stroke
				(width 0.1524)
				(type default)
			)
			(layer "B.SilkS")
		)
		(fp_rect
			(start 0.508 0.9398)
			(end -0.508 -0.9398)
			(stroke
				(width 0)
				(type default)
			)
			(fill no)
			(layer "B.CrtYd")
		)
		(fp_rect
			(start 0.508 0.9398)
			(end -0.508 -0.9398)
			(stroke
				(width 0)
				(type default)
			)
			(fill no)
			(layer "B.Fab")
		)
		(pad "1" smd custom
			(at 0 -0.4445)
			(size 0.1397 0.1397)
			(layers "B.Cu" "B.Mask" "B.Paste")
			(net "Z50_SSD_A1_SMB_CLK")
			(options
				(clearance outline)
				(anchor circle)
			)
			(primitives
				(gr_poly
					(pts
						(arc
							(start -0.1778 0.2794)
							(mid -0.249642 0.249642)
							(end -0.2794 0.1778)
						)
						(arc
							(start -0.2794 -0.1778)
							(mid -0.249642 -0.249642)
							(end -0.1778 -0.2794)
						)
						(arc
							(start 0.1778 -0.2794)
							(mid 0.249642 -0.249642)
							(end 0.2794 -0.1778)
						)
						(arc
							(start 0.2794 0.1778)
							(mid 0.249642 0.249642)
							(end 0.1778 0.2794)
						)
					)
					(width 0)
					(fill yes)
				)
			)
		)
		(pad "2" smd custom
			(at 0 0.4445)
			(size 0.1397 0.1397)
			(layers "B.Cu" "B.Mask" "B.Paste")
			(net "P1V8_PWR")
			(options
				(clearance outline)
				(anchor circle)
			)
			(primitives
				(gr_poly
					(pts
						(arc
							(start -0.1778 0.2794)
							(mid -0.249642 0.249642)
							(end -0.2794 0.1778)
						)
						(arc
							(start -0.2794 -0.1778)
							(mid -0.249642 -0.249642)
							(end -0.1778 -0.2794)
						)
						(arc
							(start 0.1778 -0.2794)
							(mid 0.249642 -0.249642)
							(end 0.2794 -0.1778)
						)
						(arc
							(start 0.2794 0.1778)
							(mid 0.249642 0.249642)
							(end 0.1778 0.2794)
						)
					)
					(width 0)
					(fill yes)
				)
			)
		)
	)
	(footprint ""
		(layer "B.Cu")
		(at 67.183 -41.402 180)
		(property "Reference" "R24"
			(at 0 0 0)
			(layer "B.SilkS")
			(hide yes)
			(effects
				(font
					(size 1.27 1.27)
				)
				(justify mirror)
			)
		)
		(property "Value" "47KR2F-GP"
			(at -0.064008 -3.993896 180)
			(unlocked yes)
			(layer "B.Fab")
			(hide yes)
			(effects
				(font
					(size 1.016 1.016)
					(thickness 0.1524)
				)
				(justify mirror)
			)
		)
		(property "Device Type" "R402H16"
			(at -0.064008 -5.517896 180)
			(unlocked yes)
			(layer "B.Fab")
			(hide yes)
			(effects
				(font
					(size 1.016 1.016)
					(thickness 0.1524)
				)
				(justify mirror)
			)
		)
		(duplicate_pad_numbers_are_jumpers no)
		(fp_line
			(start 0.508 -0.9398)
			(end 0.508 0.9398)
			(stroke
				(width 0.1524)
				(type default)
			)
			(layer "B.SilkS")
		)
		(fp_line
			(start -0.508 -0.9398)
			(end 0.508 -0.9398)
			(stroke
				(width 0.1524)
				(type default)
			)
			(layer "B.SilkS")
		)
		(fp_rect
			(start 0.508 0.9398)
			(end -0.508 -0.9398)
			(stroke
				(width 0)
				(type default)
			)
			(fill no)
			(layer "B.CrtYd")
		)
		(fp_rect
			(start 0.508 0.9398)
			(end -0.508 -0.9398)
			(stroke
				(width 0)
				(type default)
			)
			(fill no)
			(layer "B.Fab")
		)
		(pad "1" smd custom
			(at 0 -0.4445)
			(size 0.1397 0.1397)
			(layers "B.Cu" "B.Mask" "B.Paste")
			(net "P3V3_DPB")
			(options
				(clearance outline)
				(anchor circle)
			)
			(primitives
				(gr_poly
					(pts
						(arc
							(start -0.1778 0.2794)
							(mid -0.249642 0.249642)
							(end -0.2794 0.1778)
						)
						(arc
							(start -0.2794 -0.1778)
							(mid -0.249642 -0.249642)
							(end -0.1778 -0.2794)
						)
						(arc
							(start 0.1778 -0.2794)
							(mid 0.249642 -0.249642)
							(end 0.2794 -0.1778)
						)
						(arc
							(start 0.2794 0.1778)
							(mid 0.249642 0.249642)
							(end 0.1778 0.2794)
						)
					)
					(width 0)
					(fill yes)
				)
			)
		)
		(pad "2" smd custom
			(at 0 0.4445)
			(size 0.1397 0.1397)
			(layers "B.Cu" "B.Mask" "B.Paste")
			(net "Z50_SSD_B_ACT#")
			(options
				(clearance outline)
				(anchor circle)
			)
			(primitives
				(gr_poly
					(pts
						(arc
							(start -0.1778 0.2794)
							(mid -0.249642 0.249642)
							(end -0.2794 0.1778)
						)
						(arc
							(start -0.2794 -0.1778)
							(mid -0.249642 -0.249642)
							(end -0.1778 -0.2794)
						)
						(arc
							(start 0.1778 -0.2794)
							(mid 0.249642 -0.249642)
							(end 0.2794 -0.1778)
						)
						(arc
							(start 0.2794 0.1778)
							(mid 0.249642 0.249642)
							(end 0.1778 0.2794)
						)
					)
					(width 0)
					(fill yes)
				)
			)
		)
	)
	(footprint ""
		(layer "B.Cu")
		(at 37.162994 -79.629 -90)
		(property "Reference" "PR21"
			(at 0 0 90)
			(layer "B.SilkS")
			(hide yes)
			(effects
				(font
					(size 1.27 1.27)
				)
				(justify mirror)
			)
		)
		(property "Value" "2D2R3J-2-GP"
			(at 0.0254 -2.5146 270)
			(unlocked yes)
			(layer "B.Fab")
			(hide yes)
			(effects
				(font
					(size 1.016 1.016)
					(thickness 0.1524)
				)
				(justify mirror)
			)
		)
		(property "Device Type" "R603H22"
			(at 0.0254 -4.0386 270)
			(unlocked yes)
			(layer "B.Fab")
			(hide yes)
			(effects
				(font
					(size 1.016 1.016)
					(thickness 0.1524)
				)
				(justify mirror)
			)
		)
		(duplicate_pad_numbers_are_jumpers no)
		(fp_line
			(start -0.2032 0)
			(end -0.4826 0)
			(stroke
				(width 0.2032)
				(type default)
			)
			(layer "B.SilkS")
		)
		(fp_line
			(start 0.4826 0)
			(end 0.2032 0)
			(stroke
				(width 0.2032)
				(type default)
			)
			(layer "B.SilkS")
		)
		(fp_rect
			(start 0.5842 1.3335)
			(end -0.5842 -1.3335)
			(stroke
				(width 0)
				(type default)
			)
			(fill no)
			(layer "B.CrtYd")
		)
		(fp_rect
			(start 0.5842 1.3335)
			(end -0.5842 -1.3335)
			(stroke
				(width 0)
				(type default)
			)
			(fill no)
			(layer "B.Fab")
		)
		(pad "1" smd custom
			(at 0 -0.762 90)
			(size 0.2159 0.2159)
			(layers "B.Cu" "B.Mask" "B.Paste")
			(net "P3V3_DEV_VDD")
			(options
				(clearance outline)
				(anchor circle)
			)
			(primitives
				(gr_poly
					(pts
						(arc
							(start -0.3302 0.4318)
							(mid -0.402042 0.402042)
							(end -0.4318 0.3302)
						)
						(arc
							(start -0.4318 -0.3302)
							(mid -0.402042 -0.402042)
							(end -0.3302 -0.4318)
						)
						(arc
							(start 0.3302 -0.4318)
							(mid 0.402042 -0.402042)
							(end 0.4318 -0.3302)
						)
						(arc
							(start 0.4318 0.3302)
							(mid 0.402042 0.402042)
							(end 0.3302 0.4318)
						)
					)
					(width 0)
					(fill yes)
				)
			)
		)
		(pad "2" smd custom
			(at 0 0.762 90)
			(size 0.2159 0.2159)
			(layers "B.Cu" "B.Mask" "B.Paste")
			(net "P12V")
			(options
				(clearance outline)
				(anchor circle)
			)
			(primitives
				(gr_poly
					(pts
						(arc
							(start -0.3302 0.4318)
							(mid -0.402042 0.402042)
							(end -0.4318 0.3302)
						)
						(arc
							(start -0.4318 -0.3302)
							(mid -0.402042 -0.402042)
							(end -0.3302 -0.4318)
						)
						(arc
							(start 0.3302 -0.4318)
							(mid 0.402042 -0.402042)
							(end 0.4318 -0.3302)
						)
						(arc
							(start 0.4318 0.3302)
							(mid 0.402042 0.402042)
							(end 0.3302 0.4318)
						)
					)
					(width 0)
					(fill yes)
				)
			)
		)
	)
	(footprint ""
		(layer "B.Cu")
		(at 60.579 -35.179 -90)
		(property "Reference" "C35"
			(at 0 0 90)
			(layer "B.SilkS")
			(hide yes)
			(effects
				(font
					(size 1.27 1.27)
				)
				(justify mirror)
			)
		)
		(property "Value" "SC10U6D3V5KX-4GP"
			(at 0.0762 -6.1214 270)
			(unlocked yes)
			(layer "B.Fab")
			(hide yes)
			(effects
				(font
					(size 1.016 1.016)
					(thickness 0.1524)
				)
				(justify mirror)
			)
		)
		(property "Device Type" "C805H58"
			(at 0.0762 -8.1534 270)
			(unlocked yes)
			(layer "B.Fab")
			(hide yes)
			(effects
				(font
					(size 1.016 1.016)
					(thickness 0.1524)
				)
				(justify mirror)
			)
		)
		(duplicate_pad_numbers_are_jumpers no)
		(fp_line
			(start -0.635 0)
			(end 0.635 0)
			(stroke
				(width 0.508)
				(type default)
			)
			(layer "B.SilkS")
		)
		(fp_rect
			(start 0.9652 1.778)
			(end -0.9652 -1.778)
			(stroke
				(width 0)
				(type default)
			)
			(fill no)
			(layer "B.CrtYd")
		)
		(fp_poly
			(pts
				(xy 0.9652 -1.778) (xy -0.9652 -1.778) (xy -0.9652 1.778) (xy 0.9652 1.778)
			)
			(stroke
				(width 0)
				(type default)
			)
			(fill no)
			(layer "B.Fab")
		)
		(pad "1" smd rect
			(at 0 -0.9652 90)
			(size 1.397 1.143)
			(layers "B.Cu" "B.Mask" "B.Paste")
			(net "P3V3_PWR")
		)
		(pad "2" smd rect
			(at 0 0.9652 90)
			(size 1.397 1.143)
			(layers "B.Cu" "B.Mask" "B.Paste")
			(net "GND")
		)
	)
	(footprint ""
		(layer "B.Cu")
		(at 69.342 -34.417 -90)
		(property "Reference" "R48"
			(at 0 0 90)
			(layer "B.SilkS")
			(hide yes)
			(effects
				(font
					(size 1.27 1.27)
				)
				(justify mirror)
			)
		)
		(property "Value" "47KR2F-GP"
			(at -0.064008 -3.993896 270)
			(unlocked yes)
			(layer "B.Fab")
			(hide yes)
			(effects
				(font
					(size 1.016 1.016)
					(thickness 0.1524)
				)
				(justify mirror)
			)
		)
		(property "Device Type" "R402H16"
			(at -0.064008 -5.517896 270)
			(unlocked yes)
			(layer "B.Fab")
			(hide yes)
			(effects
				(font
					(size 1.016 1.016)
					(thickness 0.1524)
				)
				(justify mirror)
			)
		)
		(duplicate_pad_numbers_are_jumpers no)
		(fp_line
			(start -0.508 -0.9398)
			(end 0.508 -0.9398)
			(stroke
				(width 0.1524)
				(type default)
			)
			(layer "B.SilkS")
		)
		(fp_line
			(start 0.508 -0.9398)
			(end 0.508 0.9398)
			(stroke
				(width 0.1524)
				(type default)
			)
			(layer "B.SilkS")
		)
		(fp_rect
			(start 0.508 0.9398)
			(end -0.508 -0.9398)
			(stroke
				(width 0)
				(type default)
			)
			(fill no)
			(layer "B.CrtYd")
		)
		(fp_rect
			(start 0.508 0.9398)
			(end -0.508 -0.9398)
			(stroke
				(width 0)
				(type default)
			)
			(fill no)
			(layer "B.Fab")
		)
		(pad "1" smd custom
			(at 0 -0.4445 90)
			(size 0.1397 0.1397)
			(layers "B.Cu" "B.Mask" "B.Paste")
			(net "Z50_SSD_B_ACT#")
			(options
				(clearance outline)
				(anchor circle)
			)
			(primitives
				(gr_poly
					(pts
						(arc
							(start -0.1778 0.2794)
							(mid -0.249642 0.249642)
							(end -0.2794 0.1778)
						)
						(arc
							(start -0.2794 -0.1778)
							(mid -0.249642 -0.249642)
							(end -0.1778 -0.2794)
						)
						(arc
							(start 0.1778 -0.2794)
							(mid 0.249642 -0.249642)
							(end 0.2794 -0.1778)
						)
						(arc
							(start 0.2794 0.1778)
							(mid 0.249642 0.249642)
							(end 0.1778 0.2794)
						)
					)
					(width 0)
					(fill yes)
				)
			)
		)
		(pad "2" smd custom
			(at 0 0.4445 90)
			(size 0.1397 0.1397)
			(layers "B.Cu" "B.Mask" "B.Paste")
			(net "GND")
			(options
				(clearance outline)
				(anchor circle)
			)
			(primitives
				(gr_poly
					(pts
						(arc
							(start -0.1778 0.2794)
							(mid -0.249642 0.249642)
							(end -0.2794 0.1778)
						)
						(arc
							(start -0.2794 -0.1778)
							(mid -0.249642 -0.249642)
							(end -0.1778 -0.2794)
						)
						(arc
							(start 0.1778 -0.2794)
							(mid 0.249642 -0.249642)
							(end 0.2794 -0.1778)
						)
						(arc
							(start 0.2794 0.1778)
							(mid 0.249642 0.249642)
							(end 0.1778 0.2794)
						)
					)
					(width 0)
					(fill yes)
				)
			)
		)
	)
	(footprint ""
		(layer "B.Cu")
		(at 59.260994 -38.354 180)
		(property "Reference" "R8"
			(at 0 0 0)
			(layer "B.SilkS")
			(hide yes)
			(effects
				(font
					(size 1.27 1.27)
				)
				(justify mirror)
			)
		)
		(property "Value" "4K7R2F-GP"
			(at -0.064008 -3.993896 180)
			(unlocked yes)
			(layer "B.Fab")
			(hide yes)
			(effects
				(font
					(size 1.016 1.016)
					(thickness 0.1524)
				)
				(justify mirror)
			)
		)
		(property "Device Type" "R402H16"
			(at -0.064008 -5.517896 180)
			(unlocked yes)
			(layer "B.Fab")
			(hide yes)
			(effects
				(font
					(size 1.016 1.016)
					(thickness 0.1524)
				)
				(justify mirror)
			)
		)
		(duplicate_pad_numbers_are_jumpers no)
		(fp_line
			(start 0.508 -0.9398)
			(end 0.508 0.9398)
			(stroke
				(width 0.1524)
				(type default)
			)
			(layer "B.SilkS")
		)
		(fp_line
			(start -0.508 -0.9398)
			(end 0.508 -0.9398)
			(stroke
				(width 0.1524)
				(type default)
			)
			(layer "B.SilkS")
		)
		(fp_rect
			(start 0.508 0.9398)
			(end -0.508 -0.9398)
			(stroke
				(width 0)
				(type default)
			)
			(fill no)
			(layer "B.CrtYd")
		)
		(fp_rect
			(start 0.508 0.9398)
			(end -0.508 -0.9398)
			(stroke
				(width 0)
				(type default)
			)
			(fill no)
			(layer "B.Fab")
		)
		(pad "1" smd custom
			(at 0 -0.4445)
			(size 0.1397 0.1397)
			(layers "B.Cu" "B.Mask" "B.Paste")
			(net "P3V3_DPB")
			(options
				(clearance outline)
				(anchor circle)
			)
			(primitives
				(gr_poly
					(pts
						(arc
							(start -0.1778 0.2794)
							(mid -0.249642 0.249642)
							(end -0.2794 0.1778)
						)
						(arc
							(start -0.2794 -0.1778)
							(mid -0.249642 -0.249642)
							(end -0.1778 -0.2794)
						)
						(arc
							(start 0.1778 -0.2794)
							(mid 0.249642 -0.249642)
							(end 0.2794 -0.1778)
						)
						(arc
							(start 0.2794 0.1778)
							(mid 0.249642 0.249642)
							(end 0.1778 0.2794)
						)
					)
					(width 0)
					(fill yes)
				)
			)
		)
		(pad "2" smd custom
			(at 0 0.4445)
			(size 0.1397 0.1397)
			(layers "B.Cu" "B.Mask" "B.Paste")
			(net "Z50_TEMP_1_A0")
			(options
				(clearance outline)
				(anchor circle)
			)
			(primitives
				(gr_poly
					(pts
						(arc
							(start -0.1778 0.2794)
							(mid -0.249642 0.249642)
							(end -0.2794 0.1778)
						)
						(arc
							(start -0.2794 -0.1778)
							(mid -0.249642 -0.249642)
							(end -0.1778 -0.2794)
						)
						(arc
							(start 0.1778 -0.2794)
							(mid 0.249642 -0.249642)
							(end 0.2794 -0.1778)
						)
						(arc
							(start 0.2794 0.1778)
							(mid 0.249642 0.249642)
							(end 0.1778 0.2794)
						)
					)
					(width 0)
					(fill yes)
				)
			)
		)
	)
	(footprint ""
		(layer "B.Cu")
		(at 52.783994 -79.756 -90)
		(property "Reference" "PR38"
			(at 0 0 90)
			(layer "B.SilkS")
			(hide yes)
			(effects
				(font
					(size 1.27 1.27)
				)
				(justify mirror)
			)
		)
		(property "Value" "0R3J-0-U-GP"
			(at 0.0254 -2.5146 270)
			(unlocked yes)
			(layer "B.Fab")
			(hide yes)
			(effects
				(font
					(size 1.016 1.016)
					(thickness 0.1524)
				)
				(justify mirror)
			)
		)
		(property "Device Type" "R603H22"
			(at 0.0254 -4.0386 270)
			(unlocked yes)
			(layer "B.Fab")
			(hide yes)
			(effects
				(font
					(size 1.016 1.016)
					(thickness 0.1524)
				)
				(justify mirror)
			)
		)
		(duplicate_pad_numbers_are_jumpers no)
		(fp_line
			(start -0.2032 0)
			(end -0.4826 0)
			(stroke
				(width 0.2032)
				(type default)
			)
			(layer "B.SilkS")
		)
		(fp_line
			(start 0.4826 0)
			(end 0.2032 0)
			(stroke
				(width 0.2032)
				(type default)
			)
			(layer "B.SilkS")
		)
		(fp_rect
			(start 0.5842 1.3335)
			(end -0.5842 -1.3335)
			(stroke
				(width 0)
				(type default)
			)
			(fill no)
			(layer "B.CrtYd")
		)
		(fp_rect
			(start 0.5842 1.3335)
			(end -0.5842 -1.3335)
			(stroke
				(width 0)
				(type default)
			)
			(fill no)
			(layer "B.Fab")
		)
		(pad "1" smd custom
			(at 0 -0.762 90)
			(size 0.2159 0.2159)
			(layers "B.Cu" "B.Mask" "B.Paste")
			(net "P3V3_DEV_VBST_RC")
			(options
				(clearance outline)
				(anchor circle)
			)
			(primitives
				(gr_poly
					(pts
						(arc
							(start -0.3302 0.4318)
							(mid -0.402042 0.402042)
							(end -0.4318 0.3302)
						)
						(arc
							(start -0.4318 -0.3302)
							(mid -0.402042 -0.402042)
							(end -0.3302 -0.4318)
						)
						(arc
							(start 0.3302 -0.4318)
							(mid 0.402042 -0.402042)
							(end 0.4318 -0.3302)
						)
						(arc
							(start 0.4318 0.3302)
							(mid 0.402042 0.402042)
							(end 0.3302 0.4318)
						)
					)
					(width 0)
					(fill yes)
				)
			)
		)
		(pad "2" smd custom
			(at 0 0.762 90)
			(size 0.2159 0.2159)
			(layers "B.Cu" "B.Mask" "B.Paste")
			(net "P3V3_DEV_VBST")
			(options
				(clearance outline)
				(anchor circle)
			)
			(primitives
				(gr_poly
					(pts
						(arc
							(start -0.3302 0.4318)
							(mid -0.402042 0.402042)
							(end -0.4318 0.3302)
						)
						(arc
							(start -0.4318 -0.3302)
							(mid -0.402042 -0.402042)
							(end -0.3302 -0.4318)
						)
						(arc
							(start 0.3302 -0.4318)
							(mid 0.402042 -0.402042)
							(end 0.4318 -0.3302)
						)
						(arc
							(start 0.4318 0.3302)
							(mid 0.402042 0.402042)
							(end 0.3302 0.4318)
						)
					)
					(width 0)
					(fill yes)
				)
			)
		)
	)
)
